(kicad_pcb
	(version 20260206)
	(generator "pcbnew")
	(generator_version "10.0")
	(general
		(thickness 1.6)
		(legacy_teardrops no)
	)
	(paper "A4")
	(title_block
		(title "04192023_DAF0TMB3IC0_F0TG_MB_C_brd_V02_OCP.brd")
		(comment 1 "Grand Teton / footprints 5272-5277 of 8354")
	)
	(layers
		(0 "F.Cu" signal "TOP")
		(4 "In1.Cu" signal "GND")
		(6 "In2.Cu" signal "IN1")
		(8 "In3.Cu" signal "GND1")
		(10 "In4.Cu" signal "IN2")
		(12 "In5.Cu" signal "GND2")
		(14 "In6.Cu" signal "IN3")
		(16 "In7.Cu" signal "GND3")
		(18 "In8.Cu" signal "VCC")
		(20 "In9.Cu" signal "VCC1")
		(22 "In10.Cu" signal "GND4")
		(24 "In11.Cu" signal "IN4")
		(26 "In12.Cu" signal "GND5")
		(28 "In13.Cu" signal "IN5")
		(30 "In14.Cu" signal "GND6")
		(32 "In15.Cu" signal "IN6")
		(34 "In16.Cu" signal "GND7")
		(2 "B.Cu" signal "BOTTOM")
		(9 "F.Adhes" user "F.Adhesive")
		(11 "B.Adhes" user "B.Adhesive")
		(13 "F.Paste" user "Package Geometry/Pastemask Top")
		(15 "B.Paste" user "Package Geometry/Pastemask Bottom")
		(5 "F.SilkS" user "Ref Des/Silkscreen Top")
		(7 "B.SilkS" user "Ref Des/Silkscreen Bottom")
		(1 "F.Mask" user "Board Geometry/Soldermask Top")
		(3 "B.Mask" user "Board Geometry/Soldermask Bottom")
		(17 "Dwgs.User" user "User.Drawings")
		(19 "Cmts.User" user "User.Comments")
		(21 "Eco1.User" user "User.Eco1")
		(23 "Eco2.User" user "User.Eco2")
		(25 "Edge.Cuts" user "Board Geometry/Outline")
		(27 "Margin" user)
		(31 "F.CrtYd" user "Package Geometry/Place Bound Top")
		(29 "B.CrtYd" user "Package Geometry/Place Bound Bottom")
		(35 "F.Fab" user "Ref Des/Assembly Top")
		(33 "B.Fab" user "Ref Des/Assembly Bottom")
	)
	(footprint ""
		(layer "B.Cu")
		(at 311.778396 -395.148562 90)
		(property "Reference" "C517"
			(at 0 0 90)
			(layer "B.SilkS")
			(hide yes)
			(effects
				(font
					(size 1.27 1.27)
				)
				(justify mirror)
			)
		)
		(property "Value" ""
			(at 0 0 90)
			(layer "B.Fab")
			(effects
				(font
					(size 1.27 1.27)
				)
				(justify mirror)
			)
		)
		(duplicate_pad_numbers_are_jumpers no)
		(fp_line
			(start 0.299974 -0.150114)
			(end -0.299974 -0.150114)
			(stroke
				(width 0.1)
				(type default)
			)
			(layer "B.Fab")
		)
		(fp_line
			(start -0.299974 -0.150114)
			(end -0.299974 0.150114)
			(stroke
				(width 0.1)
				(type default)
			)
			(layer "B.Fab")
		)
		(fp_line
			(start 0.299974 0.150114)
			(end 0.299974 -0.150114)
			(stroke
				(width 0.1)
				(type default)
			)
			(layer "B.Fab")
		)
		(fp_line
			(start -0.299974 0.150114)
			(end 0.299974 0.150114)
			(stroke
				(width 0.1)
				(type default)
			)
			(layer "B.Fab")
		)
		(pad "1" smd rect
			(at 0.2667 0 270)
			(size 0.3048 0.381)
			(layers "B.Cu" "B.Mask" "B.Paste")
			(net "P1V8_CPU0_RT0_1A")
		)
		(pad "2" smd rect
			(at -0.2667 0 270)
			(size 0.3048 0.381)
			(layers "B.Cu" "B.Mask" "B.Paste")
			(net "GND")
		)
	)
	(footprint ""
		(layer "B.Cu")
		(at 350.215454 -268.41831)
		(property "Reference" "C2238"
			(at 0 0 0)
			(layer "B.SilkS")
			(hide yes)
			(effects
				(font
					(size 1.27 1.27)
				)
				(justify mirror)
			)
		)
		(property "Value" ""
			(at 0 0 0)
			(layer "B.Fab")
			(effects
				(font
					(size 1.27 1.27)
				)
				(justify mirror)
			)
		)
		(duplicate_pad_numbers_are_jumpers no)
		(fp_line
			(start -0.7874 -0.4064)
			(end -0.7874 0.4064)
			(stroke
				(width 0.1524)
				(type default)
			)
			(layer "B.SilkS")
		)
		(fp_line
			(start -0.7874 0.4064)
			(end 0.7874 0.4064)
			(stroke
				(width 0.1524)
				(type default)
			)
			(layer "B.SilkS")
		)
		(fp_line
			(start 0.7874 -0.4064)
			(end -0.7874 -0.4064)
			(stroke
				(width 0.1524)
				(type default)
			)
			(layer "B.SilkS")
		)
		(fp_line
			(start 0.7874 0.4064)
			(end 0.7874 -0.4064)
			(stroke
				(width 0.1524)
				(type default)
			)
			(layer "B.SilkS")
		)
		(fp_line
			(start -0.67945 -0.3048)
			(end -0.67945 0.3048)
			(stroke
				(width 0.1)
				(type default)
			)
			(layer "B.Fab")
		)
		(fp_line
			(start -0.67945 0.3048)
			(end -0.120396 0.3048)
			(stroke
				(width 0.1)
				(type default)
			)
			(layer "B.Fab")
		)
		(fp_line
			(start -0.12065 -0.3048)
			(end -0.67945 -0.3048)
			(stroke
				(width 0.1)
				(type default)
			)
			(layer "B.Fab")
		)
		(fp_line
			(start -0.12065 -0.2794)
			(end -0.12065 -0.3048)
			(stroke
				(width 0.1)
				(type default)
			)
			(layer "B.Fab")
		)
		(fp_line
			(start -0.120396 0.2794)
			(end 0.12065 0.2794)
			(stroke
				(width 0.1)
				(type default)
			)
			(layer "B.Fab")
		)
		(fp_line
			(start -0.120396 0.3048)
			(end -0.120396 0.2794)
			(stroke
				(width 0.1)
				(type default)
			)
			(layer "B.Fab")
		)
		(fp_line
			(start 0.12065 -0.305054)
			(end 0.12065 -0.2794)
			(stroke
				(width 0.1)
				(type default)
			)
			(layer "B.Fab")
		)
		(fp_line
			(start 0.12065 -0.2794)
			(end -0.12065 -0.2794)
			(stroke
				(width 0.1)
				(type default)
			)
			(layer "B.Fab")
		)
		(fp_line
			(start 0.12065 0.2794)
			(end 0.12065 0.3048)
			(stroke
				(width 0.1)
				(type default)
			)
			(layer "B.Fab")
		)
		(fp_line
			(start 0.12065 0.3048)
			(end 0.67945 0.3048)
			(stroke
				(width 0.1)
				(type default)
			)
			(layer "B.Fab")
		)
		(fp_line
			(start 0.67945 -0.305054)
			(end 0.12065 -0.305054)
			(stroke
				(width 0.1)
				(type default)
			)
			(layer "B.Fab")
		)
		(fp_line
			(start 0.67945 0.3048)
			(end 0.67945 -0.305054)
			(stroke
				(width 0.1)
				(type default)
			)
			(layer "B.Fab")
		)
		(pad "1" smd circle
			(at 0.40005 0 180)
			(size 0 0)
			(layers "B.Cu" "B.Mask" "B.Paste")
			(net "PVDDCR_CPU1_P0")
		)
		(pad "2" smd circle
			(at -0.40005 0 180)
			(size 0 0)
			(layers "B.Cu" "B.Mask" "B.Paste")
			(net "GND")
		)
	)
	(footprint ""
		(layer "B.Cu")
		(at 24.765 -363.347 180)
		(property "Reference" "R8247"
			(at 0 0 0)
			(layer "B.SilkS")
			(hide yes)
			(effects
				(font
					(size 1.27 1.27)
				)
				(justify mirror)
			)
		)
		(property "Value" ""
			(at 0 0 0)
			(layer "B.Fab")
			(effects
				(font
					(size 1.27 1.27)
				)
				(justify mirror)
			)
		)
		(duplicate_pad_numbers_are_jumpers no)
		(fp_line
			(start 0.7874 0.4064)
			(end 0.7874 -0.4064)
			(stroke
				(width 0.1524)
				(type default)
			)
			(layer "B.SilkS")
		)
		(fp_line
			(start 0.7874 -0.4064)
			(end -0.7874 -0.4064)
			(stroke
				(width 0.1524)
				(type default)
			)
			(layer "B.SilkS")
		)
		(fp_line
			(start -0.7874 0.4064)
			(end 0.7874 0.4064)
			(stroke
				(width 0.1524)
				(type default)
			)
			(layer "B.SilkS")
		)
		(fp_line
			(start -0.7874 -0.4064)
			(end -0.7874 0.4064)
			(stroke
				(width 0.1524)
				(type default)
			)
			(layer "B.SilkS")
		)
		(fp_line
			(start 0.67945 0.3048)
			(end 0.67945 -0.305054)
			(stroke
				(width 0.1)
				(type default)
			)
			(layer "B.Fab")
		)
		(fp_line
			(start 0.67945 -0.305054)
			(end 0.12065 -0.305054)
			(stroke
				(width 0.1)
				(type default)
			)
			(layer "B.Fab")
		)
		(fp_line
			(start 0.12065 0.3048)
			(end 0.67945 0.3048)
			(stroke
				(width 0.1)
				(type default)
			)
			(layer "B.Fab")
		)
		(fp_line
			(start 0.12065 0.2794)
			(end 0.12065 0.3048)
			(stroke
				(width 0.1)
				(type default)
			)
			(layer "B.Fab")
		)
		(fp_line
			(start 0.12065 -0.2794)
			(end -0.12065 -0.2794)
			(stroke
				(width 0.1)
				(type default)
			)
			(layer "B.Fab")
		)
		(fp_line
			(start 0.12065 -0.305054)
			(end 0.12065 -0.2794)
			(stroke
				(width 0.1)
				(type default)
			)
			(layer "B.Fab")
		)
		(fp_line
			(start -0.120396 0.3048)
			(end -0.120396 0.2794)
			(stroke
				(width 0.1)
				(type default)
			)
			(layer "B.Fab")
		)
		(fp_line
			(start -0.120396 0.2794)
			(end 0.12065 0.2794)
			(stroke
				(width 0.1)
				(type default)
			)
			(layer "B.Fab")
		)
		(fp_line
			(start -0.12065 -0.2794)
			(end -0.12065 -0.3048)
			(stroke
				(width 0.1)
				(type default)
			)
			(layer "B.Fab")
		)
		(fp_line
			(start -0.12065 -0.3048)
			(end -0.67945 -0.3048)
			(stroke
				(width 0.1)
				(type default)
			)
			(layer "B.Fab")
		)
		(fp_line
			(start -0.67945 0.3048)
			(end -0.120396 0.3048)
			(stroke
				(width 0.1)
				(type default)
			)
			(layer "B.Fab")
		)
		(fp_line
			(start -0.67945 -0.3048)
			(end -0.67945 0.3048)
			(stroke
				(width 0.1)
				(type default)
			)
			(layer "B.Fab")
		)
		(pad "1" smd circle
			(at 0.40005 0)
			(size 0 0)
			(layers "B.Cu" "B.Mask" "B.Paste")
			(net "PVDD18_S5_P1")
		)
		(pad "2" smd circle
			(at -0.40005 0)
			(size 0 0)
			(layers "B.Cu" "B.Mask" "B.Paste")
			(net "PVDDCR_CPU1_P1_RESET_N_R")
		)
	)
	(footprint ""
		(layer "B.Cu")
		(at 101.854 -413.2072 180)
		(property "Reference" "R1516"
			(at 0 0 0)
			(layer "B.SilkS")
			(hide yes)
			(effects
				(font
					(size 1.27 1.27)
				)
				(justify mirror)
			)
		)
		(property "Value" ""
			(at 0 0 0)
			(layer "B.Fab")
			(effects
				(font
					(size 1.27 1.27)
				)
				(justify mirror)
			)
		)
		(duplicate_pad_numbers_are_jumpers no)
		(fp_line
			(start 0.7874 0.4064)
			(end 0.7874 -0.4064)
			(stroke
				(width 0.1524)
				(type default)
			)
			(layer "B.SilkS")
		)
		(fp_line
			(start 0.7874 -0.4064)
			(end -0.7874 -0.4064)
			(stroke
				(width 0.1524)
				(type default)
			)
			(layer "B.SilkS")
		)
		(fp_line
			(start -0.7874 0.4064)
			(end 0.7874 0.4064)
			(stroke
				(width 0.1524)
				(type default)
			)
			(layer "B.SilkS")
		)
		(fp_line
			(start -0.7874 -0.4064)
			(end -0.7874 0.4064)
			(stroke
				(width 0.1524)
				(type default)
			)
			(layer "B.SilkS")
		)
		(fp_line
			(start 0.67945 0.3048)
			(end 0.67945 -0.305054)
			(stroke
				(width 0.1)
				(type default)
			)
			(layer "B.Fab")
		)
		(fp_line
			(start 0.67945 -0.305054)
			(end 0.12065 -0.305054)
			(stroke
				(width 0.1)
				(type default)
			)
			(layer "B.Fab")
		)
		(fp_line
			(start 0.12065 0.3048)
			(end 0.67945 0.3048)
			(stroke
				(width 0.1)
				(type default)
			)
			(layer "B.Fab")
		)
		(fp_line
			(start 0.12065 0.2794)
			(end 0.12065 0.3048)
			(stroke
				(width 0.1)
				(type default)
			)
			(layer "B.Fab")
		)
		(fp_line
			(start 0.12065 -0.2794)
			(end -0.12065 -0.2794)
			(stroke
				(width 0.1)
				(type default)
			)
			(layer "B.Fab")
		)
		(fp_line
			(start 0.12065 -0.305054)
			(end 0.12065 -0.2794)
			(stroke
				(width 0.1)
				(type default)
			)
			(layer "B.Fab")
		)
		(fp_line
			(start -0.120396 0.3048)
			(end -0.120396 0.2794)
			(stroke
				(width 0.1)
				(type default)
			)
			(layer "B.Fab")
		)
		(fp_line
			(start -0.120396 0.2794)
			(end 0.12065 0.2794)
			(stroke
				(width 0.1)
				(type default)
			)
			(layer "B.Fab")
		)
		(fp_line
			(start -0.12065 -0.2794)
			(end -0.12065 -0.3048)
			(stroke
				(width 0.1)
				(type default)
			)
			(layer "B.Fab")
		)
		(fp_line
			(start -0.12065 -0.3048)
			(end -0.67945 -0.3048)
			(stroke
				(width 0.1)
				(type default)
			)
			(layer "B.Fab")
		)
		(fp_line
			(start -0.67945 0.3048)
			(end -0.120396 0.3048)
			(stroke
				(width 0.1)
				(type default)
			)
			(layer "B.Fab")
		)
		(fp_line
			(start -0.67945 -0.3048)
			(end -0.67945 0.3048)
			(stroke
				(width 0.1)
				(type default)
			)
			(layer "B.Fab")
		)
		(pad "1" smd circle
			(at 0.40005 0)
			(size 0 0)
			(layers "B.Cu" "B.Mask" "B.Paste")
			(net "SMB_HOST_CLK_3V3AUX_SCL")
		)
		(pad "2" smd circle
			(at -0.40005 0)
			(size 0 0)
			(layers "B.Cu" "B.Mask" "B.Paste")
			(net "SMB_HOST_CLK_3V3AUX_SCL_R1")
		)
	)
	(footprint ""
		(layer "B.Cu")
		(at 402.844 -349.218504 -90)
		(property "Reference" "R6123"
			(at 0 0 90)
			(layer "B.SilkS")
			(hide yes)
			(effects
				(font
					(size 1.27 1.27)
				)
				(justify mirror)
			)
		)
		(property "Value" ""
			(at 0 0 90)
			(layer "B.Fab")
			(effects
				(font
					(size 1.27 1.27)
				)
				(justify mirror)
			)
		)
		(duplicate_pad_numbers_are_jumpers no)
		(fp_line
			(start -0.7874 0.4064)
			(end 0.7874 0.4064)
			(stroke
				(width 0.1524)
				(type default)
			)
			(layer "B.SilkS")
		)
		(fp_line
			(start 0.7874 0.4064)
			(end 0.7874 -0.4064)
			(stroke
				(width 0.1524)
				(type default)
			)
			(layer "B.SilkS")
		)
		(fp_line
			(start -0.7874 -0.4064)
			(end -0.7874 0.4064)
			(stroke
				(width 0.1524)
				(type default)
			)
			(layer "B.SilkS")
		)
		(fp_line
			(start 0.7874 -0.4064)
			(end -0.7874 -0.4064)
			(stroke
				(width 0.1524)
				(type default)
			)
			(layer "B.SilkS")
		)
		(fp_line
			(start -0.67945 0.3048)
			(end -0.120396 0.3048)
			(stroke
				(width 0.1)
				(type default)
			)
			(layer "B.Fab")
		)
		(fp_line
			(start -0.120396 0.3048)
			(end -0.120396 0.2794)
			(stroke
				(width 0.1)
				(type default)
			)
			(layer "B.Fab")
		)
		(fp_line
			(start 0.12065 0.3048)
			(end 0.67945 0.3048)
			(stroke
				(width 0.1)
				(type default)
			)
			(layer "B.Fab")
		)
		(fp_line
			(start 0.67945 0.3048)
			(end 0.67945 -0.305054)
			(stroke
				(width 0.1)
				(type default)
			)
			(layer "B.Fab")
		)
		(fp_line
			(start -0.120396 0.2794)
			(end 0.12065 0.2794)
			(stroke
				(width 0.1)
				(type default)
			)
			(layer "B.Fab")
		)
		(fp_line
			(start 0.12065 0.2794)
			(end 0.12065 0.3048)
			(stroke
				(width 0.1)
				(type default)
			)
			(layer "B.Fab")
		)
		(fp_line
			(start -0.12065 -0.2794)
			(end -0.12065 -0.3048)
			(stroke
				(width 0.1)
				(type default)
			)
			(layer "B.Fab")
		)
		(fp_line
			(start 0.12065 -0.2794)
			(end -0.12065 -0.2794)
			(stroke
				(width 0.1)
				(type default)
			)
			(layer "B.Fab")
		)
		(fp_line
			(start -0.67945 -0.3048)
			(end -0.67945 0.3048)
			(stroke
				(width 0.1)
				(type default)
			)
			(layer "B.Fab")
		)
		(fp_line
			(start -0.12065 -0.3048)
			(end -0.67945 -0.3048)
			(stroke
				(width 0.1)
				(type default)
			)
			(layer "B.Fab")
		)
		(fp_line
			(start 0.12065 -0.305054)
			(end 0.12065 -0.2794)
			(stroke
				(width 0.1)
				(type default)
			)
			(layer "B.Fab")
		)
		(fp_line
			(start 0.67945 -0.305054)
			(end 0.12065 -0.305054)
			(stroke
				(width 0.1)
				(type default)
			)
			(layer "B.Fab")
		)
		(pad "1" smd circle
			(at 0.40005 0 90)
			(size 0 0)
			(layers "B.Cu" "B.Mask" "B.Paste")
			(net "PVDD18_S5_P0")
		)
		(pad "2" smd circle
			(at -0.40005 0 90)
			(size 0 0)
			(layers "B.Cu" "B.Mask" "B.Paste")
			(net "FM_BOARD_SKU_ID1")
		)
	)
	(footprint ""
		(layer "B.Cu")
		(at 197.269608 -117.689376 180)
		(property "Reference" "R4170"
			(at 0 0 0)
			(layer "B.SilkS")
			(hide yes)
			(effects
				(font
					(size 1.27 1.27)
				)
				(justify mirror)
			)
		)
		(property "Value" ""
			(at 0 0 0)
			(layer "B.Fab")
			(effects
				(font
					(size 1.27 1.27)
				)
				(justify mirror)
			)
		)
		(duplicate_pad_numbers_are_jumpers no)
		(fp_line
			(start 0.7874 0.4064)
			(end 0.7874 -0.4064)
			(stroke
				(width 0.1524)
				(type default)
			)
			(layer "B.SilkS")
		)
		(fp_line
			(start 0.7874 -0.4064)
			(end -0.7874 -0.4064)
			(stroke
				(width 0.1524)
				(type default)
			)
			(layer "B.SilkS")
		)
		(fp_line
			(start -0.7874 0.4064)
			(end 0.7874 0.4064)
			(stroke
				(width 0.1524)
				(type default)
			)
			(layer "B.SilkS")
		)
		(fp_line
			(start -0.7874 -0.4064)
			(end -0.7874 0.4064)
			(stroke
				(width 0.1524)
				(type default)
			)
			(layer "B.SilkS")
		)
		(fp_line
			(start 0.67945 0.3048)
			(end 0.67945 -0.305054)
			(stroke
				(width 0.1)
				(type default)
			)
			(layer "B.Fab")
		)
		(fp_line
			(start 0.67945 -0.305054)
			(end 0.12065 -0.305054)
			(stroke
				(width 0.1)
				(type default)
			)
			(layer "B.Fab")
		)
		(fp_line
			(start 0.12065 0.3048)
			(end 0.67945 0.3048)
			(stroke
				(width 0.1)
				(type default)
			)
			(layer "B.Fab")
		)
		(fp_line
			(start 0.12065 0.2794)
			(end 0.12065 0.3048)
			(stroke
				(width 0.1)
				(type default)
			)
			(layer "B.Fab")
		)
		(fp_line
			(start 0.12065 -0.2794)
			(end -0.12065 -0.2794)
			(stroke
				(width 0.1)
				(type default)
			)
			(layer "B.Fab")
		)
		(fp_line
			(start 0.12065 -0.305054)
			(end 0.12065 -0.2794)
			(stroke
				(width 0.1)
				(type default)
			)
			(layer "B.Fab")
		)
		(fp_line
			(start -0.120396 0.3048)
			(end -0.120396 0.2794)
			(stroke
				(width 0.1)
				(type default)
			)
			(layer "B.Fab")
		)
		(fp_line
			(start -0.120396 0.2794)
			(end 0.12065 0.2794)
			(stroke
				(width 0.1)
				(type default)
			)
			(layer "B.Fab")
		)
		(fp_line
			(start -0.12065 -0.2794)
			(end -0.12065 -0.3048)
			(stroke
				(width 0.1)
				(type default)
			)
			(layer "B.Fab")
		)
		(fp_line
			(start -0.12065 -0.3048)
			(end -0.67945 -0.3048)
			(stroke
				(width 0.1)
				(type default)
			)
			(layer "B.Fab")
		)
		(fp_line
			(start -0.67945 0.3048)
			(end -0.120396 0.3048)
			(stroke
				(width 0.1)
				(type default)
			)
			(layer "B.Fab")
		)
		(fp_line
			(start -0.67945 -0.3048)
			(end -0.67945 0.3048)
			(stroke
				(width 0.1)
				(type default)
			)
			(layer "B.Fab")
		)
		(pad "1" smd circle
			(at 0.40005 0)
			(size 0 0)
			(layers "B.Cu" "B.Mask" "B.Paste")
			(net "GPU_3V3IO_RSVD1_ISO_R")
		)
		(pad "2" smd circle
			(at -0.40005 0)
			(size 0 0)
			(layers "B.Cu" "B.Mask" "B.Paste")
			(net "GPU_3V3IO_RSVD1_ISO")
		)
	)
)
